(kicad_pcb
	(version 20260206)
	(generator "pcbnew")
	(generator_version "10.0")
	(general
		(thickness 1.6)
		(legacy_teardrops no)
	)
	(paper "A4")
	(title_block
		(title "peb — Lightning_PEB_BRD.brd")
		(comment 1 "Lightning (Wiwynn / Facebook NVMe JBOF) / footprints 907-912 of 2563")
	)
	(layers
		(0 "F.Cu" signal "TOP")
		(4 "In1.Cu" signal "L2GND")
		(6 "In2.Cu" signal "L3")
		(8 "In3.Cu" signal "L4VCC")
		(10 "In4.Cu" signal "L5VCC")
		(12 "In5.Cu" signal "L6")
		(14 "In6.Cu" signal "L7GND")
		(2 "B.Cu" signal "BOTTOM")
		(9 "F.Adhes" user "F.Adhesive")
		(11 "B.Adhes" user "B.Adhesive")
		(13 "F.Paste" user "Package Geometry/Pastemask Top")
		(15 "B.Paste" user "Package Geometry/Pastemask Bottom")
		(5 "F.SilkS" user "Ref Des/Silkscreen Top")
		(7 "B.SilkS" user "Ref Des/Silkscreen Bottom")
		(1 "F.Mask" user "Board Geometry/Soldermask Top")
		(3 "B.Mask" user "Board Geometry/Soldermask Bottom")
		(17 "Dwgs.User" user "User.Drawings")
		(19 "Cmts.User" user "User.Comments")
		(21 "Eco1.User" user "User.Eco1")
		(23 "Eco2.User" user "User.Eco2")
		(25 "Edge.Cuts" user "Board Geometry/Outline")
		(27 "Margin" user)
		(31 "F.CrtYd" user "Package Geometry/Place Bound Top")
		(29 "B.CrtYd" user "Package Geometry/Place Bound Bottom")
		(35 "F.Fab" user "Ref Des/Assembly Top")
		(33 "B.Fab" user "Ref Des/Assembly Bottom")
	)
	(footprint ""
		(layer "F.Cu")
		(at 227.584 -1.143 180)
		(property "Reference" "C4"
			(at 0 0 180)
			(layer "F.SilkS")
			(hide yes)
			(effects
				(font
					(size 1.27 1.27)
				)
			)
		)
		(property "Value" "SCD1U16V2KX-3GP"
			(at 1.1811 -2.7051 180)
			(unlocked yes)
			(layer "F.Fab")
			(hide yes)
			(effects
				(font
					(size 1.016 1.016)
					(thickness 0.1524)
				)
			)
		)
		(property "Device Type" "C402H22"
			(at 1.1811 -4.2291 180)
			(unlocked yes)
			(layer "F.Fab")
			(hide yes)
			(effects
				(font
					(size 1.016 1.016)
					(thickness 0.1524)
				)
			)
		)
		(duplicate_pad_numbers_are_jumpers no)
		(fp_rect
			(start -0.4318 0.9525)
			(end 0.4318 -0.9525)
			(stroke
				(width 0)
				(type default)
			)
			(fill no)
			(layer "F.CrtYd")
		)
		(fp_rect
			(start -0.4318 0.9525)
			(end 0.4318 -0.9525)
			(stroke
				(width 0)
				(type default)
			)
			(fill no)
			(layer "F.Fab")
		)
		(pad "1" smd custom
			(at 0 -0.4445 180)
			(size 0.1524 0.1524)
			(layers "F.Cu" "F.Mask" "F.Paste")
			(net "P3V3_STBY")
			(options
				(clearance outline)
				(anchor circle)
			)
			(primitives
				(gr_poly
					(pts
						(arc
							(start 0.3048 -0.2032)
							(mid 0.275042 -0.275042)
							(end 0.2032 -0.3048)
						)
						(arc
							(start -0.2032 -0.3048)
							(mid -0.275042 -0.275042)
							(end -0.3048 -0.2032)
						)
						(arc
							(start -0.3048 0.2032)
							(mid -0.275042 0.275042)
							(end -0.2032 0.3048)
						)
						(arc
							(start 0.2032 0.3048)
							(mid 0.275042 0.275042)
							(end 0.3048 0.2032)
						)
					)
					(width 0)
					(fill yes)
				)
			)
		)
		(pad "2" smd custom
			(at 0 0.4445 180)
			(size 0.1524 0.1524)
			(layers "F.Cu" "F.Mask" "F.Paste")
			(net "GND")
			(options
				(clearance outline)
				(anchor circle)
			)
			(primitives
				(gr_poly
					(pts
						(arc
							(start 0.3048 -0.2032)
							(mid 0.275042 -0.275042)
							(end 0.2032 -0.3048)
						)
						(arc
							(start -0.2032 -0.3048)
							(mid -0.275042 -0.275042)
							(end -0.3048 -0.2032)
						)
						(arc
							(start -0.3048 0.2032)
							(mid -0.275042 0.275042)
							(end -0.2032 0.3048)
						)
						(arc
							(start 0.2032 0.3048)
							(mid 0.275042 0.275042)
							(end 0.3048 0.2032)
						)
					)
					(width 0)
					(fill yes)
				)
			)
		)
	)
	(footprint ""
		(layer "F.Cu")
		(at 320.559176 -33.507426)
		(property "Reference" "C46"
			(at 0 0 0)
			(layer "F.SilkS")
			(hide yes)
			(effects
				(font
					(size 1.27 1.27)
				)
			)
		)
		(property "Value" "SCD22U10V2KX-1GP"
			(at 1.1811 -2.7051 0)
			(unlocked yes)
			(layer "F.Fab")
			(hide yes)
			(effects
				(font
					(size 1.016 1.016)
					(thickness 0.1524)
				)
			)
		)
		(property "Device Type" "C402H22"
			(at 1.1811 -4.2291 0)
			(unlocked yes)
			(layer "F.Fab")
			(hide yes)
			(effects
				(font
					(size 1.016 1.016)
					(thickness 0.1524)
				)
			)
		)
		(duplicate_pad_numbers_are_jumpers no)
		(fp_rect
			(start -0.4318 0.9525)
			(end 0.4318 -0.9525)
			(stroke
				(width 0)
				(type default)
			)
			(fill no)
			(layer "F.CrtYd")
		)
		(fp_rect
			(start -0.4318 0.9525)
			(end 0.4318 -0.9525)
			(stroke
				(width 0)
				(type default)
			)
			(fill no)
			(layer "F.Fab")
		)
		(pad "1" smd custom
			(at 0 -0.4445)
			(size 0.1524 0.1524)
			(layers "F.Cu" "F.Mask" "F.Paste")
			(net "PCIE_TX_CAP_N12")
			(options
				(clearance outline)
				(anchor circle)
			)
			(primitives
				(gr_poly
					(pts
						(arc
							(start 0.3048 -0.2032)
							(mid 0.275042 -0.275042)
							(end 0.2032 -0.3048)
						)
						(arc
							(start -0.2032 -0.3048)
							(mid -0.275042 -0.275042)
							(end -0.3048 -0.2032)
						)
						(arc
							(start -0.3048 0.2032)
							(mid -0.275042 0.275042)
							(end -0.2032 0.3048)
						)
						(arc
							(start 0.2032 0.3048)
							(mid 0.275042 0.275042)
							(end 0.3048 0.2032)
						)
					)
					(width 0)
					(fill yes)
				)
			)
		)
		(pad "2" smd custom
			(at 0 0.4445)
			(size 0.1524 0.1524)
			(layers "F.Cu" "F.Mask" "F.Paste")
			(net "PCIE_TX_N12")
			(options
				(clearance outline)
				(anchor circle)
			)
			(primitives
				(gr_poly
					(pts
						(arc
							(start 0.3048 -0.2032)
							(mid 0.275042 -0.275042)
							(end 0.2032 -0.3048)
						)
						(arc
							(start -0.2032 -0.3048)
							(mid -0.275042 -0.275042)
							(end -0.3048 -0.2032)
						)
						(arc
							(start -0.3048 0.2032)
							(mid -0.275042 0.275042)
							(end -0.2032 0.3048)
						)
						(arc
							(start 0.2032 0.3048)
							(mid 0.275042 0.275042)
							(end 0.3048 0.2032)
						)
					)
					(width 0)
					(fill yes)
				)
			)
		)
	)
	(footprint ""
		(layer "F.Cu")
		(at 85.3948 -52.6288 180)
		(property "Reference" "JP1"
			(at 0 0 180)
			(layer "F.SilkS")
			(hide yes)
			(effects
				(font
					(size 1.27 1.27)
				)
			)
		)
		(property "Value" "PIN-CON3-S-GP"
			(at -5.588 -5.3086 180)
			(unlocked yes)
			(layer "F.Fab")
			(hide yes)
			(effects
				(font
					(size 1.016 1.016)
					(thickness 0.1524)
				)
			)
		)
		(property "Device Type" "21S-91-03GB01"
			(at -5.588 -6.8326 180)
			(unlocked yes)
			(layer "F.Fab")
			(hide yes)
			(effects
				(font
					(size 1.016 1.016)
					(thickness 0.1524)
				)
			)
		)
		(duplicate_pad_numbers_are_jumpers no)
		(fp_line
			(start 3.8862 1.4986)
			(end 3.8862 -1.4986)
			(stroke
				(width 0.1524)
				(type default)
			)
			(layer "F.SilkS")
		)
		(fp_line
			(start 3.8862 -1.4986)
			(end -3.8862 -1.4986)
			(stroke
				(width 0.1524)
				(type default)
			)
			(layer "F.SilkS")
		)
		(fp_line
			(start -3.8862 1.4986)
			(end 3.8862 1.4986)
			(stroke
				(width 0.1524)
				(type default)
			)
			(layer "F.SilkS")
		)
		(fp_line
			(start -3.8862 -1.4986)
			(end -3.8862 1.4986)
			(stroke
				(width 0.1524)
				(type default)
			)
			(layer "F.SilkS")
		)
		(fp_line
			(start -4.0132 -0.3556)
			(end -4.0132 -1.6256)
			(stroke
				(width 0.4064)
				(type default)
			)
			(layer "F.SilkS")
		)
		(fp_line
			(start -4.0132 -1.6256)
			(end -2.7432 -1.6256)
			(stroke
				(width 0.4064)
				(type default)
			)
			(layer "F.SilkS")
		)
		(fp_circle
			(center 2.54 0)
			(end 1.4732 0)
			(stroke
				(width 0.3048)
				(type default)
			)
			(fill no)
			(layer "F.SilkS")
		)
		(fp_circle
			(center 0 0)
			(end -1.0668 0)
			(stroke
				(width 0.3048)
				(type default)
			)
			(fill no)
			(layer "F.SilkS")
		)
		(fp_circle
			(center -2.54 0)
			(end -3.6068 0)
			(stroke
				(width 0.3048)
				(type default)
			)
			(fill no)
			(layer "F.SilkS")
		)
		(fp_rect
			(start -3.6322 1.2446)
			(end 3.6322 -1.2446)
			(stroke
				(width 0)
				(type default)
			)
			(fill no)
			(layer "F.CrtYd")
		)
		(fp_poly
			(pts
				(xy 4.1402 -1.2446) (xy -3.6322 -1.2446) (xy -3.6322 1.2446) (xy 3.6322 1.2446) (xy 3.6322 -1.2319)
				(xy 4.1402 -1.2319) (xy 4.1402 1.7526) (xy -4.1402 1.7526) (xy -4.1402 -1.7526) (xy 4.1402 -1.7526)
			)
			(stroke
				(width 0)
				(type default)
			)
			(fill no)
			(layer "F.CrtYd")
		)
		(fp_rect
			(start -4.1402 1.7526)
			(end 4.1402 -1.7526)
			(stroke
				(width 0)
				(type default)
			)
			(fill no)
			(layer "F.Fab")
		)
		(pad "1" thru_hole circle
			(at -2.54 0 180)
			(size 1.4224 1.4224)
			(drill 1.016)
			(layers "*.Cu" "*.Mask")
			(remove_unused_layers no)
			(net "ROMA0")
			(clearance 0.1524)
			(thermal_gap 0.1524)
		)
		(pad "2" thru_hole circle
			(at 0 0 180)
			(size 1.4224 1.4224)
			(drill 1.016)
			(layers "*.Cu" "*.Mask")
			(remove_unused_layers no)
			(net "AS_ROMA0_R")
			(clearance 0.1524)
			(thermal_gap 0.1524)
		)
		(pad "3" thru_hole circle
			(at 2.54 0 180)
			(size 1.4224 1.4224)
			(drill 1.016)
			(layers "*.Cu" "*.Mask")
			(remove_unused_layers no)
			(net "Net_517")
			(clearance 0.1524)
			(thermal_gap 0.1524)
		)
	)
	(footprint ""
		(layer "F.Cu")
		(at 28.2956 -186.7662 180)
		(property "Reference" "C259"
			(at 0 0 180)
			(layer "F.SilkS")
			(hide yes)
			(effects
				(font
					(size 1.27 1.27)
				)
			)
		)
		(property "Value" "SC220P50V3JN-GP"
			(at 0 -2.8194 180)
			(unlocked yes)
			(layer "F.Fab")
			(hide yes)
			(effects
				(font
					(size 1.016 1.016)
					(thickness 0.1524)
				)
			)
		)
		(property "Device Type" "C603H36"
			(at 0 -4.3434 180)
			(unlocked yes)
			(layer "F.Fab")
			(hide yes)
			(effects
				(font
					(size 1.016 1.016)
					(thickness 0.1524)
				)
			)
		)
		(duplicate_pad_numbers_are_jumpers no)
		(fp_line
			(start 0.508 0)
			(end -0.508 0)
			(stroke
				(width 0.2032)
				(type default)
			)
			(layer "F.SilkS")
		)
		(fp_rect
			(start -0.5842 1.3335)
			(end 0.5842 -1.3335)
			(stroke
				(width 0)
				(type default)
			)
			(fill no)
			(layer "F.CrtYd")
		)
		(fp_rect
			(start -0.5842 1.3335)
			(end 0.5842 -1.3335)
			(stroke
				(width 0)
				(type default)
			)
			(fill no)
			(layer "F.Fab")
		)
		(pad "1" smd custom
			(at 0 -0.762 180)
			(size 0.2159 0.2159)
			(layers "F.Cu" "F.Mask" "F.Paste")
			(net "BMC_I2C5_SCL_R")
			(options
				(clearance outline)
				(anchor circle)
			)
			(primitives
				(gr_poly
					(pts
						(arc
							(start -0.3302 -0.4318)
							(mid -0.402042 -0.402042)
							(end -0.4318 -0.3302)
						)
						(arc
							(start -0.4318 0.3302)
							(mid -0.402042 0.402042)
							(end -0.3302 0.4318)
						)
						(arc
							(start 0.3302 0.4318)
							(mid 0.402042 0.402042)
							(end 0.4318 0.3302)
						)
						(arc
							(start 0.4318 -0.3302)
							(mid 0.402042 -0.402042)
							(end 0.3302 -0.4318)
						)
					)
					(width 0)
					(fill yes)
				)
			)
		)
		(pad "2" smd custom
			(at 0 0.762 180)
			(size 0.2159 0.2159)
			(layers "F.Cu" "F.Mask" "F.Paste")
			(net "GND")
			(options
				(clearance outline)
				(anchor circle)
			)
			(primitives
				(gr_poly
					(pts
						(arc
							(start -0.3302 -0.4318)
							(mid -0.402042 -0.402042)
							(end -0.4318 -0.3302)
						)
						(arc
							(start -0.4318 0.3302)
							(mid -0.402042 0.402042)
							(end -0.3302 0.4318)
						)
						(arc
							(start 0.3302 0.4318)
							(mid 0.402042 0.402042)
							(end 0.4318 0.3302)
						)
						(arc
							(start 0.4318 -0.3302)
							(mid 0.402042 -0.402042)
							(end 0.3302 -0.4318)
						)
					)
					(width 0)
					(fill yes)
				)
			)
		)
	)
	(footprint ""
		(layer "F.Cu")
		(at 36.322 -98.552 90)
		(property "Reference" "U50"
			(at 0 0 90)
			(layer "F.SilkS")
			(hide yes)
			(effects
				(font
					(size 1.27 1.27)
				)
			)
		)
		(property "Value" "SN74CBTLV3257RGYR-1-GP"
			(at -3.774948 -0.185674 90)
			(unlocked yes)
			(layer "F.Fab")
			(hide yes)
			(effects
				(font
					(size 1.016 1.016)
					(thickness 0.1524)
				)
			)
		)
		(property "Device Type" "QFN16G3540-G215265H40"
			(at -3.774948 -1.709674 90)
			(unlocked yes)
			(layer "F.Fab")
			(hide yes)
			(effects
				(font
					(size 1.016 1.016)
					(thickness 0.1524)
				)
			)
		)
		(duplicate_pad_numbers_are_jumpers no)
		(fp_line
			(start -3.0099 -2.7686)
			(end -1.7399 -2.7686)
			(stroke
				(width 0.1524)
				(type default)
			)
			(layer "F.SilkS")
		)
		(fp_line
			(start -0.249936 -2.54)
			(end -0.249936 -3.048)
			(stroke
				(width 0.1524)
				(type default)
			)
			(layer "F.SilkS")
		)
		(fp_line
			(start -3.0099 -1.4986)
			(end -3.0099 -2.7686)
			(stroke
				(width 0.1524)
				(type default)
			)
			(layer "F.SilkS")
		)
		(fp_line
			(start 3.0099 1.4986)
			(end 3.0099 2.7686)
			(stroke
				(width 0.1524)
				(type default)
			)
			(layer "F.SilkS")
		)
		(fp_line
			(start -3.0099 1.4986)
			(end -3.0099 2.7686)
			(stroke
				(width 0.1524)
				(type default)
			)
			(layer "F.SilkS")
		)
		(fp_line
			(start 1.249934 2.54)
			(end 1.249934 3.048)
			(stroke
				(width 0.1524)
				(type default)
			)
			(layer "F.SilkS")
		)
		(fp_line
			(start -1.249934 2.54)
			(end -1.249934 3.302)
			(stroke
				(width 0.1524)
				(type default)
			)
			(layer "F.SilkS")
		)
		(fp_line
			(start 3.0099 2.7686)
			(end 1.7399 2.7686)
			(stroke
				(width 0.1524)
				(type default)
			)
			(layer "F.SilkS")
		)
		(fp_line
			(start -3.0099 2.7686)
			(end -1.7399 2.7686)
			(stroke
				(width 0.1524)
				(type default)
			)
			(layer "F.SilkS")
		)
		(fp_poly
			(pts
				(xy 1.7399 -2.7686) (xy 3.0099 -1.4986) (xy 3.0099 -2.7686)
			)
			(stroke
				(width 0)
				(type default)
			)
			(fill yes)
			(layer "F.SilkS")
		)
		(fp_rect
			(start -1.9939 1.7526)
			(end 1.9939 -1.7526)
			(stroke
				(width 0)
				(type default)
			)
			(fill no)
			(layer "F.CrtYd")
		)
		(fp_poly
			(pts
				(xy -3.0099 2.7686) (xy -3.0099 -2.7686) (xy 3.0099 -2.7686) (xy 3.0099 -0.2286) (xy 1.9939 -0.2286)
				(xy 1.9939 -1.7526) (xy -1.9939 -1.7526) (xy -1.9939 1.7526) (xy 1.9939 1.7526) (xy 1.9939 -0.22352)
				(xy 3.0099 -0.22352) (xy 3.0099 2.7686)
			)
			(stroke
				(width 0)
				(type default)
			)
			(fill no)
			(layer "F.CrtYd")
		)
		(fp_rect
			(start -3.0099 2.7686)
			(end 3.0099 -2.7686)
			(stroke
				(width 0)
				(type default)
			)
			(fill no)
			(layer "F.Fab")
		)
		(pad "1" smd rect
			(at 2.0193 -0.750062 90)
			(size 0.9652 0.3048)
			(layers "F.Cu" "F.Mask" "F.Paste")
			(net "SPI_FLASH_SELECT_R")
		)
		(pad "2" smd rect
			(at 1.249934 -1.778 90)
			(size 0.3048 0.9652)
			(layers "F.Cu" "F.Mask" "F.Paste")
			(net "SPICS0_N")
		)
		(pad "3" smd rect
			(at 0.750062 -1.778 90)
			(size 0.3048 0.9652)
			(layers "F.Cu" "F.Mask" "F.Paste")
			(net "I210_CS_N_R")
		)
		(pad "4" smd rect
			(at 0.249936 -1.778 90)
			(size 0.3048 0.9652)
			(layers "F.Cu" "F.Mask" "F.Paste")
			(net "I2C_MUX_1A")
		)
		(pad "5" smd rect
			(at -0.249936 -1.778 90)
			(size 0.3048 0.9652)
			(layers "F.Cu" "F.Mask" "F.Paste")
			(net "SPICK")
		)
		(pad "6" smd rect
			(at -0.750062 -1.778 90)
			(size 0.3048 0.9652)
			(layers "F.Cu" "F.Mask" "F.Paste")
			(net "I210_SK_R")
		)
		(pad "7" smd rect
			(at -1.249934 -1.778 90)
			(size 0.3048 0.9652)
			(layers "F.Cu" "F.Mask" "F.Paste")
			(net "I2C_MUX_2A")
		)
		(pad "8" smd rect
			(at -2.0193 -0.750062 90)
			(size 0.9652 0.3048)
			(layers "F.Cu" "F.Mask" "F.Paste")
			(net "GND")
		)
		(pad "9" smd rect
			(at -2.0193 0.75311 90)
			(size 0.9652 0.3048)
			(layers "F.Cu" "F.Mask" "F.Paste")
			(net "I2C_MUX_3A")
		)
		(pad "10" smd rect
			(at -1.249934 1.778 90)
			(size 0.3048 0.9652)
			(layers "F.Cu" "F.Mask" "F.Paste")
			(net "I210_SO_R")
		)
		(pad "11" smd rect
			(at -0.750062 1.778 90)
			(size 0.3048 0.9652)
			(layers "F.Cu" "F.Mask" "F.Paste")
			(net "SPIDO")
		)
		(pad "12" smd rect
			(at -0.249936 1.778 90)
			(size 0.3048 0.9652)
			(layers "F.Cu" "F.Mask" "F.Paste")
			(net "I2C_MUX_4A")
		)
		(pad "13" smd rect
			(at 0.249936 1.778 90)
			(size 0.3048 0.9652)
			(layers "F.Cu" "F.Mask" "F.Paste")
			(net "I210_SI_R")
		)
		(pad "14" smd rect
			(at 0.750062 1.778 90)
			(size 0.3048 0.9652)
			(layers "F.Cu" "F.Mask" "F.Paste")
			(net "SPIDI")
		)
		(pad "15" smd rect
			(at 1.249934 1.778 90)
			(size 0.3048 0.9652)
			(layers "F.Cu" "F.Mask" "F.Paste")
			(net "BUS_SW_OE#")
		)
		(pad "16" smd rect
			(at 2.0193 0.750062 90)
			(size 0.9652 0.3048)
			(layers "F.Cu" "F.Mask" "F.Paste")
			(net "P3V3_I2C_MUX")
		)
		(pad "17" smd rect
			(at 0 0 90)
			(size 2.6416 2.159)
			(layers "F.Cu" "F.Mask" "F.Paste")
			(net "GND")
		)
	)
	(footprint ""
		(layer "F.Cu")
		(at 331.978 -71.247 180)
		(property "Reference" "PR152"
			(at 0 0 180)
			(layer "F.SilkS")
			(hide yes)
			(effects
				(font
					(size 1.27 1.27)
				)
			)
		)
		(property "Value" "0R2J-2-GP"
			(at 0.064008 -3.993896 180)
			(unlocked yes)
			(layer "F.Fab")
			(hide yes)
			(effects
				(font
					(size 1.016 1.016)
					(thickness 0.1524)
				)
			)
		)
		(property "Device Type" "R402H16"
			(at 0.064008 -5.517896 180)
			(unlocked yes)
			(layer "F.Fab")
			(hide yes)
			(effects
				(font
					(size 1.016 1.016)
					(thickness 0.1524)
				)
			)
		)
		(duplicate_pad_numbers_are_jumpers no)
		(fp_line
			(start 0.508 -0.9398)
			(end -0.508 -0.9398)
			(stroke
				(width 0.1524)
				(type default)
			)
			(layer "F.SilkS")
		)
		(fp_line
			(start -0.508 -0.9398)
			(end -0.508 0.9398)
			(stroke
				(width 0.1524)
				(type default)
			)
			(layer "F.SilkS")
		)
		(fp_rect
			(start -0.508 0.9398)
			(end 0.508 -0.9398)
			(stroke
				(width 0)
				(type default)
			)
			(fill no)
			(layer "F.CrtYd")
		)
		(fp_rect
			(start -0.508 0.9398)
			(end 0.508 -0.9398)
			(stroke
				(width 0)
				(type default)
			)
			(fill no)
			(layer "F.Fab")
		)
		(pad "1" smd custom
			(at 0 -0.4445 180)
			(size 0.1397 0.1397)
			(layers "F.Cu" "F.Mask" "F.Paste")
			(net "P0V9_E_EN")
			(options
				(clearance outline)
				(anchor circle)
			)
			(primitives
				(gr_poly
					(pts
						(arc
							(start -0.1778 -0.2794)
							(mid -0.249642 -0.249642)
							(end -0.2794 -0.1778)
						)
						(arc
							(start -0.2794 0.1778)
							(mid -0.249642 0.249642)
							(end -0.1778 0.2794)
						)
						(arc
							(start 0.1778 0.2794)
							(mid 0.249642 0.249642)
							(end 0.2794 0.1778)
						)
						(arc
							(start 0.2794 -0.1778)
							(mid 0.249642 -0.249642)
							(end 0.1778 -0.2794)
						)
					)
					(width 0)
					(fill yes)
				)
			)
		)
		(pad "2" smd custom
			(at 0 0.4445 180)
			(size 0.1397 0.1397)
			(layers "F.Cu" "F.Mask" "F.Paste")
			(net "P0V9_PG")
			(options
				(clearance outline)
				(anchor circle)
			)
			(primitives
				(gr_poly
					(pts
						(arc
							(start -0.1778 -0.2794)
							(mid -0.249642 -0.249642)
							(end -0.2794 -0.1778)
						)
						(arc
							(start -0.2794 0.1778)
							(mid -0.249642 0.249642)
							(end -0.1778 0.2794)
						)
						(arc
							(start 0.1778 0.2794)
							(mid 0.249642 0.249642)
							(end 0.2794 0.1778)
						)
						(arc
							(start 0.2794 -0.1778)
							(mid 0.249642 -0.249642)
							(end 0.1778 -0.2794)
						)
					)
					(width 0)
					(fill yes)
				)
			)
		)
	)
)
